(kicad_pcb
	(version 20260206)
	(generator "pcbnew")
	(generator_version "10.0")
	(general
		(thickness 1.6)
		(legacy_teardrops no)
	)
	(paper "A4")
	(title_block
		(title "04192023_DAF0TMB3IC0_F0TG_MB_C_brd_V02_OCP.brd")
		(comment 1 "Grand Teton / footprints 6413-6419 of 8354")
	)
	(layers
		(0 "F.Cu" signal "TOP")
		(4 "In1.Cu" signal "GND")
		(6 "In2.Cu" signal "IN1")
		(8 "In3.Cu" signal "GND1")
		(10 "In4.Cu" signal "IN2")
		(12 "In5.Cu" signal "GND2")
		(14 "In6.Cu" signal "IN3")
		(16 "In7.Cu" signal "GND3")
		(18 "In8.Cu" signal "VCC")
		(20 "In9.Cu" signal "VCC1")
		(22 "In10.Cu" signal "GND4")
		(24 "In11.Cu" signal "IN4")
		(26 "In12.Cu" signal "GND5")
		(28 "In13.Cu" signal "IN5")
		(30 "In14.Cu" signal "GND6")
		(32 "In15.Cu" signal "IN6")
		(34 "In16.Cu" signal "GND7")
		(2 "B.Cu" signal "BOTTOM")
		(9 "F.Adhes" user "F.Adhesive")
		(11 "B.Adhes" user "B.Adhesive")
		(13 "F.Paste" user "Package Geometry/Pastemask Top")
		(15 "B.Paste" user "Package Geometry/Pastemask Bottom")
		(5 "F.SilkS" user "Ref Des/Silkscreen Top")
		(7 "B.SilkS" user "Ref Des/Silkscreen Bottom")
		(1 "F.Mask" user "Board Geometry/Soldermask Top")
		(3 "B.Mask" user "Board Geometry/Soldermask Bottom")
		(17 "Dwgs.User" user "User.Drawings")
		(19 "Cmts.User" user "User.Comments")
		(21 "Eco1.User" user "User.Eco1")
		(23 "Eco2.User" user "User.Eco2")
		(25 "Edge.Cuts" user "Board Geometry/Outline")
		(27 "Margin" user)
		(31 "F.CrtYd" user "Package Geometry/Place Bound Top")
		(29 "B.CrtYd" user "Package Geometry/Place Bound Bottom")
		(35 "F.Fab" user "Ref Des/Assembly Top")
		(33 "B.Fab" user "Ref Des/Assembly Bottom")
	)
	(footprint ""
		(layer "B.Cu")
		(at 61.413898 -15.58036 90)
		(property "Reference" "R3216"
			(at 0 0 90)
			(layer "B.SilkS")
			(hide yes)
			(effects
				(font
					(size 1.27 1.27)
				)
				(justify mirror)
			)
		)
		(property "Value" ""
			(at 0 0 90)
			(layer "B.Fab")
			(effects
				(font
					(size 1.27 1.27)
				)
				(justify mirror)
			)
		)
		(duplicate_pad_numbers_are_jumpers no)
		(fp_line
			(start 0.7874 -0.4064)
			(end -0.7874 -0.4064)
			(stroke
				(width 0.1524)
				(type default)
			)
			(layer "B.SilkS")
		)
		(fp_line
			(start -0.7874 -0.4064)
			(end -0.7874 0.4064)
			(stroke
				(width 0.1524)
				(type default)
			)
			(layer "B.SilkS")
		)
		(fp_line
			(start 0.7874 0.4064)
			(end 0.7874 -0.4064)
			(stroke
				(width 0.1524)
				(type default)
			)
			(layer "B.SilkS")
		)
		(fp_line
			(start -0.7874 0.4064)
			(end 0.7874 0.4064)
			(stroke
				(width 0.1524)
				(type default)
			)
			(layer "B.SilkS")
		)
		(fp_line
			(start 0.67945 -0.305054)
			(end 0.12065 -0.305054)
			(stroke
				(width 0.1)
				(type default)
			)
			(layer "B.Fab")
		)
		(fp_line
			(start 0.12065 -0.305054)
			(end 0.12065 -0.2794)
			(stroke
				(width 0.1)
				(type default)
			)
			(layer "B.Fab")
		)
		(fp_line
			(start -0.12065 -0.3048)
			(end -0.67945 -0.3048)
			(stroke
				(width 0.1)
				(type default)
			)
			(layer "B.Fab")
		)
		(fp_line
			(start -0.67945 -0.3048)
			(end -0.67945 0.3048)
			(stroke
				(width 0.1)
				(type default)
			)
			(layer "B.Fab")
		)
		(fp_line
			(start 0.12065 -0.2794)
			(end -0.12065 -0.2794)
			(stroke
				(width 0.1)
				(type default)
			)
			(layer "B.Fab")
		)
		(fp_line
			(start -0.12065 -0.2794)
			(end -0.12065 -0.3048)
			(stroke
				(width 0.1)
				(type default)
			)
			(layer "B.Fab")
		)
		(fp_line
			(start 0.12065 0.2794)
			(end 0.12065 0.3048)
			(stroke
				(width 0.1)
				(type default)
			)
			(layer "B.Fab")
		)
		(fp_line
			(start -0.120396 0.2794)
			(end 0.12065 0.2794)
			(stroke
				(width 0.1)
				(type default)
			)
			(layer "B.Fab")
		)
		(fp_line
			(start 0.67945 0.3048)
			(end 0.67945 -0.305054)
			(stroke
				(width 0.1)
				(type default)
			)
			(layer "B.Fab")
		)
		(fp_line
			(start 0.12065 0.3048)
			(end 0.67945 0.3048)
			(stroke
				(width 0.1)
				(type default)
			)
			(layer "B.Fab")
		)
		(fp_line
			(start -0.120396 0.3048)
			(end -0.120396 0.2794)
			(stroke
				(width 0.1)
				(type default)
			)
			(layer "B.Fab")
		)
		(fp_line
			(start -0.67945 0.3048)
			(end -0.120396 0.3048)
			(stroke
				(width 0.1)
				(type default)
			)
			(layer "B.Fab")
		)
		(pad "1" smd circle
			(at 0.40005 0 270)
			(size 0 0)
			(layers "B.Cu" "B.Mask" "B.Paste")
			(net "OCP_V3_2_ISO_BIF1_EN")
		)
		(pad "2" smd circle
			(at -0.40005 0 270)
			(size 0 0)
			(layers "B.Cu" "B.Mask" "B.Paste")
			(net "GND")
		)
	)
	(footprint ""
		(layer "B.Cu")
		(at 22.70506 -244.085364 180)
		(property "Reference" "R505"
			(at 0 0 0)
			(layer "B.SilkS")
			(hide yes)
			(effects
				(font
					(size 1.27 1.27)
				)
				(justify mirror)
			)
		)
		(property "Value" ""
			(at 0 0 0)
			(layer "B.Fab")
			(effects
				(font
					(size 1.27 1.27)
				)
				(justify mirror)
			)
		)
		(duplicate_pad_numbers_are_jumpers no)
		(fp_line
			(start 0.7874 0.4064)
			(end 0.7874 -0.4064)
			(stroke
				(width 0.1524)
				(type default)
			)
			(layer "B.SilkS")
		)
		(fp_line
			(start 0.7874 -0.4064)
			(end -0.7874 -0.4064)
			(stroke
				(width 0.1524)
				(type default)
			)
			(layer "B.SilkS")
		)
		(fp_line
			(start -0.7874 0.4064)
			(end 0.7874 0.4064)
			(stroke
				(width 0.1524)
				(type default)
			)
			(layer "B.SilkS")
		)
		(fp_line
			(start -0.7874 -0.4064)
			(end -0.7874 0.4064)
			(stroke
				(width 0.1524)
				(type default)
			)
			(layer "B.SilkS")
		)
		(fp_line
			(start 0.67945 0.3048)
			(end 0.67945 -0.305054)
			(stroke
				(width 0.1)
				(type default)
			)
			(layer "B.Fab")
		)
		(fp_line
			(start 0.67945 -0.305054)
			(end 0.12065 -0.305054)
			(stroke
				(width 0.1)
				(type default)
			)
			(layer "B.Fab")
		)
		(fp_line
			(start 0.12065 0.3048)
			(end 0.67945 0.3048)
			(stroke
				(width 0.1)
				(type default)
			)
			(layer "B.Fab")
		)
		(fp_line
			(start 0.12065 0.2794)
			(end 0.12065 0.3048)
			(stroke
				(width 0.1)
				(type default)
			)
			(layer "B.Fab")
		)
		(fp_line
			(start 0.12065 -0.2794)
			(end -0.12065 -0.2794)
			(stroke
				(width 0.1)
				(type default)
			)
			(layer "B.Fab")
		)
		(fp_line
			(start 0.12065 -0.305054)
			(end 0.12065 -0.2794)
			(stroke
				(width 0.1)
				(type default)
			)
			(layer "B.Fab")
		)
		(fp_line
			(start -0.120396 0.3048)
			(end -0.120396 0.2794)
			(stroke
				(width 0.1)
				(type default)
			)
			(layer "B.Fab")
		)
		(fp_line
			(start -0.120396 0.2794)
			(end 0.12065 0.2794)
			(stroke
				(width 0.1)
				(type default)
			)
			(layer "B.Fab")
		)
		(fp_line
			(start -0.12065 -0.2794)
			(end -0.12065 -0.3048)
			(stroke
				(width 0.1)
				(type default)
			)
			(layer "B.Fab")
		)
		(fp_line
			(start -0.12065 -0.3048)
			(end -0.67945 -0.3048)
			(stroke
				(width 0.1)
				(type default)
			)
			(layer "B.Fab")
		)
		(fp_line
			(start -0.67945 0.3048)
			(end -0.120396 0.3048)
			(stroke
				(width 0.1)
				(type default)
			)
			(layer "B.Fab")
		)
		(fp_line
			(start -0.67945 -0.3048)
			(end -0.67945 0.3048)
			(stroke
				(width 0.1)
				(type default)
			)
			(layer "B.Fab")
		)
		(pad "1" smd circle
			(at 0.40005 0)
			(size 0 0)
			(layers "B.Cu" "B.Mask" "B.Paste")
			(net "M_F_CPU1_ALERT_N")
		)
		(pad "2" smd circle
			(at -0.40005 0)
			(size 0 0)
			(layers "B.Cu" "B.Mask" "B.Paste")
			(net "M_F_CPU1_ALERT_R_N")
		)
	)
	(footprint ""
		(layer "B.Cu")
		(at 26.206958 -382.874012 -90)
		(property "Reference" "PC6807"
			(at 0 0 90)
			(layer "B.SilkS")
			(hide yes)
			(effects
				(font
					(size 1.27 1.27)
				)
				(justify mirror)
			)
		)
		(property "Value" ""
			(at 0 0 90)
			(layer "B.Fab")
			(effects
				(font
					(size 1.27 1.27)
				)
				(justify mirror)
			)
		)
		(duplicate_pad_numbers_are_jumpers no)
		(fp_line
			(start -0.7874 0.4064)
			(end 0.7874 0.4064)
			(stroke
				(width 0.1524)
				(type default)
			)
			(layer "B.SilkS")
		)
		(fp_line
			(start 0.7874 0.4064)
			(end 0.7874 -0.4064)
			(stroke
				(width 0.1524)
				(type default)
			)
			(layer "B.SilkS")
		)
		(fp_line
			(start -0.7874 -0.4064)
			(end -0.7874 0.4064)
			(stroke
				(width 0.1524)
				(type default)
			)
			(layer "B.SilkS")
		)
		(fp_line
			(start 0.7874 -0.4064)
			(end -0.7874 -0.4064)
			(stroke
				(width 0.1524)
				(type default)
			)
			(layer "B.SilkS")
		)
		(fp_line
			(start -0.67945 0.3048)
			(end -0.120396 0.3048)
			(stroke
				(width 0.1)
				(type default)
			)
			(layer "B.Fab")
		)
		(fp_line
			(start -0.120396 0.3048)
			(end -0.120396 0.2794)
			(stroke
				(width 0.1)
				(type default)
			)
			(layer "B.Fab")
		)
		(fp_line
			(start 0.12065 0.3048)
			(end 0.67945 0.3048)
			(stroke
				(width 0.1)
				(type default)
			)
			(layer "B.Fab")
		)
		(fp_line
			(start 0.67945 0.3048)
			(end 0.67945 -0.305054)
			(stroke
				(width 0.1)
				(type default)
			)
			(layer "B.Fab")
		)
		(fp_line
			(start -0.120396 0.2794)
			(end 0.12065 0.2794)
			(stroke
				(width 0.1)
				(type default)
			)
			(layer "B.Fab")
		)
		(fp_line
			(start 0.12065 0.2794)
			(end 0.12065 0.3048)
			(stroke
				(width 0.1)
				(type default)
			)
			(layer "B.Fab")
		)
		(fp_line
			(start -0.12065 -0.2794)
			(end -0.12065 -0.3048)
			(stroke
				(width 0.1)
				(type default)
			)
			(layer "B.Fab")
		)
		(fp_line
			(start 0.12065 -0.2794)
			(end -0.12065 -0.2794)
			(stroke
				(width 0.1)
				(type default)
			)
			(layer "B.Fab")
		)
		(fp_line
			(start -0.67945 -0.3048)
			(end -0.67945 0.3048)
			(stroke
				(width 0.1)
				(type default)
			)
			(layer "B.Fab")
		)
		(fp_line
			(start -0.12065 -0.3048)
			(end -0.67945 -0.3048)
			(stroke
				(width 0.1)
				(type default)
			)
			(layer "B.Fab")
		)
		(fp_line
			(start 0.12065 -0.305054)
			(end 0.12065 -0.2794)
			(stroke
				(width 0.1)
				(type default)
			)
			(layer "B.Fab")
		)
		(fp_line
			(start 0.67945 -0.305054)
			(end 0.12065 -0.305054)
			(stroke
				(width 0.1)
				(type default)
			)
			(layer "B.Fab")
		)
		(pad "1" smd circle
			(at 0.40005 0 90)
			(size 0 0)
			(layers "B.Cu" "B.Mask" "B.Paste")
			(net "P0V9_CPU1_RT_2D")
		)
		(pad "2" smd circle
			(at -0.40005 0 90)
			(size 0 0)
			(layers "B.Cu" "B.Mask" "B.Paste")
			(net "GND")
		)
	)
	(footprint ""
		(layer "B.Cu")
		(at 350.318832 -259.729986 180)
		(property "Reference" "C2611"
			(at 0 0 0)
			(layer "B.SilkS")
			(hide yes)
			(effects
				(font
					(size 1.27 1.27)
				)
				(justify mirror)
			)
		)
		(property "Value" ""
			(at 0 0 0)
			(layer "B.Fab")
			(effects
				(font
					(size 1.27 1.27)
				)
				(justify mirror)
			)
		)
		(duplicate_pad_numbers_are_jumpers no)
		(fp_line
			(start 0.7874 0.4064)
			(end 0.7874 -0.4064)
			(stroke
				(width 0.1524)
				(type default)
			)
			(layer "B.SilkS")
		)
		(fp_line
			(start 0.7874 -0.4064)
			(end -0.7874 -0.4064)
			(stroke
				(width 0.1524)
				(type default)
			)
			(layer "B.SilkS")
		)
		(fp_line
			(start -0.7874 0.4064)
			(end 0.7874 0.4064)
			(stroke
				(width 0.1524)
				(type default)
			)
			(layer "B.SilkS")
		)
		(fp_line
			(start -0.7874 -0.4064)
			(end -0.7874 0.4064)
			(stroke
				(width 0.1524)
				(type default)
			)
			(layer "B.SilkS")
		)
		(fp_line
			(start 0.67945 0.3048)
			(end 0.67945 -0.305054)
			(stroke
				(width 0.1)
				(type default)
			)
			(layer "B.Fab")
		)
		(fp_line
			(start 0.67945 -0.305054)
			(end 0.12065 -0.305054)
			(stroke
				(width 0.1)
				(type default)
			)
			(layer "B.Fab")
		)
		(fp_line
			(start 0.12065 0.3048)
			(end 0.67945 0.3048)
			(stroke
				(width 0.1)
				(type default)
			)
			(layer "B.Fab")
		)
		(fp_line
			(start 0.12065 0.2794)
			(end 0.12065 0.3048)
			(stroke
				(width 0.1)
				(type default)
			)
			(layer "B.Fab")
		)
		(fp_line
			(start 0.12065 -0.2794)
			(end -0.12065 -0.2794)
			(stroke
				(width 0.1)
				(type default)
			)
			(layer "B.Fab")
		)
		(fp_line
			(start 0.12065 -0.305054)
			(end 0.12065 -0.2794)
			(stroke
				(width 0.1)
				(type default)
			)
			(layer "B.Fab")
		)
		(fp_line
			(start -0.120396 0.3048)
			(end -0.120396 0.2794)
			(stroke
				(width 0.1)
				(type default)
			)
			(layer "B.Fab")
		)
		(fp_line
			(start -0.120396 0.2794)
			(end 0.12065 0.2794)
			(stroke
				(width 0.1)
				(type default)
			)
			(layer "B.Fab")
		)
		(fp_line
			(start -0.12065 -0.2794)
			(end -0.12065 -0.3048)
			(stroke
				(width 0.1)
				(type default)
			)
			(layer "B.Fab")
		)
		(fp_line
			(start -0.12065 -0.3048)
			(end -0.67945 -0.3048)
			(stroke
				(width 0.1)
				(type default)
			)
			(layer "B.Fab")
		)
		(fp_line
			(start -0.67945 0.3048)
			(end -0.120396 0.3048)
			(stroke
				(width 0.1)
				(type default)
			)
			(layer "B.Fab")
		)
		(fp_line
			(start -0.67945 -0.3048)
			(end -0.67945 0.3048)
			(stroke
				(width 0.1)
				(type default)
			)
			(layer "B.Fab")
		)
		(pad "1" smd circle
			(at 0.40005 0)
			(size 0 0)
			(layers "B.Cu" "B.Mask" "B.Paste")
			(net "PVDDIO_P0")
		)
		(pad "2" smd circle
			(at -0.40005 0)
			(size 0 0)
			(layers "B.Cu" "B.Mask" "B.Paste")
			(net "GND")
		)
	)
	(footprint ""
		(layer "B.Cu")
		(at 156.746194 -388.011162 -90)
		(property "Reference" "C379"
			(at 0 0 90)
			(layer "B.SilkS")
			(hide yes)
			(effects
				(font
					(size 1.27 1.27)
				)
				(justify mirror)
			)
		)
		(property "Value" ""
			(at 0 0 90)
			(layer "B.Fab")
			(effects
				(font
					(size 1.27 1.27)
				)
				(justify mirror)
			)
		)
		(duplicate_pad_numbers_are_jumpers no)
		(fp_line
			(start -0.299974 0.150114)
			(end 0.299974 0.150114)
			(stroke
				(width 0.1)
				(type default)
			)
			(layer "B.Fab")
		)
		(fp_line
			(start 0.299974 0.150114)
			(end 0.299974 -0.150114)
			(stroke
				(width 0.1)
				(type default)
			)
			(layer "B.Fab")
		)
		(fp_line
			(start -0.299974 -0.150114)
			(end -0.299974 0.150114)
			(stroke
				(width 0.1)
				(type default)
			)
			(layer "B.Fab")
		)
		(fp_line
			(start 0.299974 -0.150114)
			(end -0.299974 -0.150114)
			(stroke
				(width 0.1)
				(type default)
			)
			(layer "B.Fab")
		)
		(pad "1" smd rect
			(at 0.2667 0 90)
			(size 0.3048 0.381)
			(layers "B.Cu" "B.Mask" "B.Paste")
			(net "P1V8_CPU1_RT2_1A")
		)
		(pad "2" smd rect
			(at -0.2667 0 90)
			(size 0.3048 0.381)
			(layers "B.Cu" "B.Mask" "B.Paste")
			(net "GND")
		)
	)
	(footprint ""
		(layer "B.Cu")
		(at 90.209878 -144.88541)
		(property "Reference" "PC247"
			(at 0 0 0)
			(layer "B.SilkS")
			(hide yes)
			(effects
				(font
					(size 1.27 1.27)
				)
				(justify mirror)
			)
		)
		(property "Value" ""
			(at 0 0 0)
			(layer "B.Fab")
			(effects
				(font
					(size 1.27 1.27)
				)
				(justify mirror)
			)
		)
		(duplicate_pad_numbers_are_jumpers no)
		(fp_line
			(start -0.7874 -0.4064)
			(end -0.7874 0.4064)
			(stroke
				(width 0.1524)
				(type default)
			)
			(layer "B.SilkS")
		)
		(fp_line
			(start -0.7874 0.4064)
			(end 0.7874 0.4064)
			(stroke
				(width 0.1524)
				(type default)
			)
			(layer "B.SilkS")
		)
		(fp_line
			(start 0.7874 -0.4064)
			(end -0.7874 -0.4064)
			(stroke
				(width 0.1524)
				(type default)
			)
			(layer "B.SilkS")
		)
		(fp_line
			(start 0.7874 0.4064)
			(end 0.7874 -0.4064)
			(stroke
				(width 0.1524)
				(type default)
			)
			(layer "B.SilkS")
		)
		(fp_line
			(start -0.67945 -0.3048)
			(end -0.67945 0.3048)
			(stroke
				(width 0.1)
				(type default)
			)
			(layer "B.Fab")
		)
		(fp_line
			(start -0.67945 0.3048)
			(end -0.120396 0.3048)
			(stroke
				(width 0.1)
				(type default)
			)
			(layer "B.Fab")
		)
		(fp_line
			(start -0.12065 -0.3048)
			(end -0.67945 -0.3048)
			(stroke
				(width 0.1)
				(type default)
			)
			(layer "B.Fab")
		)
		(fp_line
			(start -0.12065 -0.2794)
			(end -0.12065 -0.3048)
			(stroke
				(width 0.1)
				(type default)
			)
			(layer "B.Fab")
		)
		(fp_line
			(start -0.120396 0.2794)
			(end 0.12065 0.2794)
			(stroke
				(width 0.1)
				(type default)
			)
			(layer "B.Fab")
		)
		(fp_line
			(start -0.120396 0.3048)
			(end -0.120396 0.2794)
			(stroke
				(width 0.1)
				(type default)
			)
			(layer "B.Fab")
		)
		(fp_line
			(start 0.12065 -0.305054)
			(end 0.12065 -0.2794)
			(stroke
				(width 0.1)
				(type default)
			)
			(layer "B.Fab")
		)
		(fp_line
			(start 0.12065 -0.2794)
			(end -0.12065 -0.2794)
			(stroke
				(width 0.1)
				(type default)
			)
			(layer "B.Fab")
		)
		(fp_line
			(start 0.12065 0.2794)
			(end 0.12065 0.3048)
			(stroke
				(width 0.1)
				(type default)
			)
			(layer "B.Fab")
		)
		(fp_line
			(start 0.12065 0.3048)
			(end 0.67945 0.3048)
			(stroke
				(width 0.1)
				(type default)
			)
			(layer "B.Fab")
		)
		(fp_line
			(start 0.67945 -0.305054)
			(end 0.12065 -0.305054)
			(stroke
				(width 0.1)
				(type default)
			)
			(layer "B.Fab")
		)
		(fp_line
			(start 0.67945 0.3048)
			(end 0.67945 -0.305054)
			(stroke
				(width 0.1)
				(type default)
			)
			(layer "B.Fab")
		)
		(pad "1" smd circle
			(at 0.40005 0 180)
			(size 0 0)
			(layers "B.Cu" "B.Mask" "B.Paste")
			(net "PVDD18_S5_P1")
		)
		(pad "2" smd circle
			(at -0.40005 0 180)
			(size 0 0)
			(layers "B.Cu" "B.Mask" "B.Paste")
			(net "GND")
		)
	)
	(footprint ""
		(layer "B.Cu")
		(at 408.721814 -151.614124 90)
		(property "Reference" "PC1852"
			(at 0 0 90)
			(layer "B.SilkS")
			(hide yes)
			(effects
				(font
					(size 1.27 1.27)
				)
				(justify mirror)
			)
		)
		(property "Value" ""
			(at 0 0 90)
			(layer "B.Fab")
			(effects
				(font
					(size 1.27 1.27)
				)
				(justify mirror)
			)
		)
		(duplicate_pad_numbers_are_jumpers no)
		(fp_line
			(start 0.7874 -0.4064)
			(end -0.7874 -0.4064)
			(stroke
				(width 0.1524)
				(type default)
			)
			(layer "B.SilkS")
		)
		(fp_line
			(start -0.7874 -0.4064)
			(end -0.7874 0.4064)
			(stroke
				(width 0.1524)
				(type default)
			)
			(layer "B.SilkS")
		)
		(fp_line
			(start 0.7874 0.4064)
			(end 0.7874 -0.4064)
			(stroke
				(width 0.1524)
				(type default)
			)
			(layer "B.SilkS")
		)
		(fp_line
			(start -0.7874 0.4064)
			(end 0.7874 0.4064)
			(stroke
				(width 0.1524)
				(type default)
			)
			(layer "B.SilkS")
		)
		(fp_line
			(start 0.67945 -0.305054)
			(end 0.12065 -0.305054)
			(stroke
				(width 0.1)
				(type default)
			)
			(layer "B.Fab")
		)
		(fp_line
			(start 0.12065 -0.305054)
			(end 0.12065 -0.2794)
			(stroke
				(width 0.1)
				(type default)
			)
			(layer "B.Fab")
		)
		(fp_line
			(start -0.12065 -0.3048)
			(end -0.67945 -0.3048)
			(stroke
				(width 0.1)
				(type default)
			)
			(layer "B.Fab")
		)
		(fp_line
			(start -0.67945 -0.3048)
			(end -0.67945 0.3048)
			(stroke
				(width 0.1)
				(type default)
			)
			(layer "B.Fab")
		)
		(fp_line
			(start 0.12065 -0.2794)
			(end -0.12065 -0.2794)
			(stroke
				(width 0.1)
				(type default)
			)
			(layer "B.Fab")
		)
		(fp_line
			(start -0.12065 -0.2794)
			(end -0.12065 -0.3048)
			(stroke
				(width 0.1)
				(type default)
			)
			(layer "B.Fab")
		)
		(fp_line
			(start 0.12065 0.2794)
			(end 0.12065 0.3048)
			(stroke
				(width 0.1)
				(type default)
			)
			(layer "B.Fab")
		)
		(fp_line
			(start -0.120396 0.2794)
			(end 0.12065 0.2794)
			(stroke
				(width 0.1)
				(type default)
			)
			(layer "B.Fab")
		)
		(fp_line
			(start 0.67945 0.3048)
			(end 0.67945 -0.305054)
			(stroke
				(width 0.1)
				(type default)
			)
			(layer "B.Fab")
		)
		(fp_line
			(start 0.12065 0.3048)
			(end 0.67945 0.3048)
			(stroke
				(width 0.1)
				(type default)
			)
			(layer "B.Fab")
		)
		(fp_line
			(start -0.120396 0.3048)
			(end -0.120396 0.2794)
			(stroke
				(width 0.1)
				(type default)
			)
			(layer "B.Fab")
		)
		(fp_line
			(start -0.67945 0.3048)
			(end -0.120396 0.3048)
			(stroke
				(width 0.1)
				(type default)
			)
			(layer "B.Fab")
		)
		(pad "1" smd circle
			(at 0.40005 0 270)
			(size 0 0)
			(layers "B.Cu" "B.Mask" "B.Paste")
			(net "P5V_AUX")
		)
		(pad "2" smd circle
			(at -0.40005 0 270)
			(size 0 0)
			(layers "B.Cu" "B.Mask" "B.Paste")
			(net "GND")
		)
	)
)
